FILE_TYPE = CONNECTIVITY;
{Allegro Design Entry HDL 16.6-p007 (v16-6-112F) 10/10/2012}
"PAGE_NUMBER" = 214;
0"NC";
1"GND\g";
2"PVCCIO_CPU1\g";
3"GND\g";
4"GND\g";
5"GND\g";
6"GND\g";
7"GND\g";
8"PVCCIO_CPU1\g";
9"VR_FET_SW_P12V_STBY_PVCCIN_CPU0\g";
10"GND\g";
11"GND\g";
12"PVCCIO_CPU1\g";
13"GND\g";
14"GND\g";
15"GND\g";
16"P5V_STBY\g";
17"VR_FET_SW_P12V_STBY_PVCCIN_CPU0\g";
18"GND\g";
19"A_TSENSE_PVCCIO_CPU1";
20"VR_PVCCIO_CPU1_PH1_SW";
21"UN$214$3D01R5F-GP$I132$2";
22"NC_PVCCIO_CPU1_PH1_P31";
23"VR_PVCCIO_CPU1_PH1_PHASE";
24"VR_PVCCIO_CPU1_PH1_BOOT_R";
25"VSENSE_PVCCIO_CPU1_AVSP";
26"VR_PVCCIO_CPU1_PH1_BOOT";
27"VSENSE_PVCCIO_CPU1_AVSN";
28"VR_PVCCIO_CPU1_PWM1";
29"ISENSE_PVCCIO_CPU1_PH1_IMON";
30"VR_PVCCIO_CPU1_PH1_VCIN";
31"VR_PVCCIO_CPU1_AIREF1";
32"VR_PVCCIO_CPU1_OCSET";
33"TP_PVCCIO_CPU1_GL_0";
34"TP_PVCCIO_CPU1_GL_1";
35"VSENSE_PVCCIO_CPU1_SKT_VSEN";
36"VSENSE_PVCCIO_CPU1_SKT_VRTN";
%"RES"
"1","(-500,1050)","0","mstr_discrete","I101";
;
CDS_SEC"1"
ROOM"PVCCIO_CPU1"
SEC"1"
BOM_COST"PROC_VRD_VCCIO_CPU1"
CDS_LOCATION"R3D28"
SEC_TYPE"0402"
CDS_LIB"mstr_discrete"
TOLERANCE"1%"
WATTAGE"1/16W"
VALUE"100.0"
PART_NUMBER"G21796-017"
PACK_TYPE"0402"
MATERIAL"CHIP"
LOCATION"R3D28";
"B"
$PN"2"1;
"A"
$PN"1"27;
%"GND"
"1","(-250,825)","0","mstr_symbols","I102";
;
ROOM"PVCCIO_CPU0"
BOM_COST"MEM_VRD_PVCCIO_CPU0"
VOLTAGE"0"
CDS_LIB"mstr_symbols"
SIZE"1B"
BODY_TYPE"PLUMBING"
HDL_POWER"GND";
"A\NAC"1;
%"RES"
"1","(-500,2250)","0","mstr_discrete","I105";
;
CDS_SEC"1"
CDS_LOCATION"R3E1"
ROOM"PVCCIO_CPU1"
SEC"1"
SEC_TYPE"0402"
BOM_COST"PROC_VRD_VCCIO_CPU1"
CDS_LIB"mstr_discrete"
PART_NUMBER"G21796-017"
WATTAGE"1/16W"
PACK_TYPE"0402"
LOCATION"R3E1"
MATERIAL"CHIP"
TOLERANCE"1%"
VALUE"100.0";
"B"
$PN"2"2;
"A"
$PN"1"25;
%"PVCCIO_CPU1"
"1","(-250,2525)","0","mstr_symbols","I107";
;
VOLTAGE"1.1V"
BODY_TYPE"PLUMBING"
CDS_LIB"mstr_symbols"
HDL_POWER"PVCCIO_CPU1";
"G\NAC"2;
%"CAP_A"
"1","(3575,3000)","0","dev_discrete","I108";
;
CDS_LIB"dev_discrete"
CDS_LOCATION"C3E1"
REUSE_ID"281"
BOM_COST"PROC_VRD_PVCCIO_CPU1"
CDS_SEC"1"
$SEC"1"
ROOM"PVCCIO_CPU1"
VOLTAGE"4V"
PACK_TYPE"0603V"
TOLERANCE"20%"
PART_NUMBER"E15431-004"
VALUE"22.0UF"
MATERIAL"X6S"
LOCATION"C3E1";
"B"
$PN"2"13;
"A"
$PN"1"12;
%"RES"
"2","(3875,2975)","0","mstr_discrete","I109";
;
CDS_LIB"mstr_discrete"
CDS_LOCATION"R7R1"
$SEC"1"
CDS_SEC"1"
PACK_TYPE"0402"
TOLERANCE"1.0%"
MATERIAL"CHIP"
WATTAGE"1/16W"
VALUE"51.1"
LOCATION"R7R1"
PART_NUMBER"G21796-208";
"A"
$PN"1"12;
"B"
$PN"2"13;
%"IR354XX"
"1","(850,3475)","0","mstr_discrete","I126";
;
CDS_SEC"1"
CDS_LIB"mstr_discrete"
SEC_TYPE"SM"
SEC"1"
CDS_LOCATION"EU4E2"
PACK_TYPE"SM"
NO_XNET_CONNECTION"1"
MATERIAL"IC"
VALUE"IR35412"
LOCATION"EU4E2"
PART_NUMBER"H73684-001";
"TOUT_FLT"
$PN"36"19;
"NC"
$PN"31"22;
"OCSET"
$PN"37"32;
"IOUT"
$PN"38"29;
"SW"
$PN"10"20;
"BOOST"
$PN"33"24;
"REFIN"
$PN"39"31;
"PWM"
$PN"34"28;
"PHASE"
$PN"32"23;
"VIN<0>"
$PN"25"17;
"VCC"
$PN"3"30;
"VIN<1>"
$PN"30"17;
"EN"
$PN"35"16;
"VDRV"
$PN"4"16;
"VOS"
$PN"1"12;
"LGND"
$PN"2"14;
"PGND<1>"
$PN"7"14;
"PGND<2>"
$PN"40"14;
"PGND<0>"
$PN"5"14;
"GL<0>"
$PN"6"33;
"GL<1>"
$PN"41"34;
%"RES"
"2","(3175,3625)","0","mstr_discrete","I127";
;
CDS_LOCATION"R4E21"
CDS_LIB"mstr_discrete"
CDS_SEC"1"
$SEC"1"
PACK_TYPE"0402"
PART_NUMBER"G21796-187"
MATERIAL"EMPTY"
TOLERANCE"1%"
WATTAGE"1/16W"
VALUE"68.1K"
LOCATION"R4E21";
"A"
$PN"1"32;
"B"
$PN"2"3;
%"GND"
"1","(3175,3375)","0","mstr_symbols","I128";
;
BOM_COST"PROC_VRD_VCCIN_CPU0"
ROOM"PVSA_CPU1_PWR_VR"
SIZE"1B"
CDS_LIB"mstr_symbols"
BODY_TYPE"PLUMBING"
VOLTAGE"0"
HDL_POWER"GND";
"A\NAC"3;
%"SHUNT"
"1","(-1125,1750)","0","mstr_misc","I129";
;
CDS_SEC"1"
CDS_LOCATION"SH3D2"
PIN_SHORT"A:B"
PACK_TYPE"SH0201"
MATERIAL"EMPTY"
CDS_LIB"mstr_misc"
SEC"1"
SEC_TYPE"SH0201"
PART_NUMBER"N_A"
LOCATION"SH3D2";
"A"
$PN"1"35;
"B"
$PN"2"25;
%"SHUNT"
"1","(-1125,1300)","0","mstr_misc","I130";
;
CDS_SEC"1"
CDS_LOCATION"SH3D1"
PIN_SHORT"A:B"
PACK_TYPE"SH0201"
MATERIAL"EMPTY"
SEC"1"
SEC_TYPE"SH0201"
CDS_LIB"mstr_misc"
PART_NUMBER"N_A"
LOCATION"SH3D1";
"A"
$PN"1"36;
"B"
$PN"2"27;
%"SC2K2P50V3KX-GP"
"1","(2150,3025)","0","w_hdl","I131";
;
CDS_SEC"1"
$SEC"1"
CDS_LOCATION"CT62"
CDS_LMAN_SYM_OUTLINE"-50,25,50,-25"
CDS_LIB"w_hdl"
PART_NUMBER"78.22224.2BL"
PACK_TYPE"SMD-BCG6"
STATUS"NOPOP"
VALUE"SC2K2P50V3KX-GP"
LOCATION"CT62";
"2"
$PN"2"21;
"1"
$PN"1"20;
%"3D01R5F-GP"
"1","(2150,2725)","4","w_hdl","I132";
;
CDS_SEC"1"
$SEC"1"
CDS_LOCATION"RT42"
CDS_LMAN_SYM_OUTLINE"-50,75,50,-75"
CDS_LIB"w_hdl"
PART_NUMBER"64.3R015.16L"
PACK_TYPE"SMD-RG5"
LOCATION"RT42"
STATUS"NOPOP"
VALUE"3D01R5F-GP";
"2"
$PN"2"21;
"1"
$PN"1"4;
%"GND"
"1","(2150,2525)","0","mstr_symbols","I133";
;
HDL_POWER"GND"
SIZE"1B"
VOLTAGE"0"
BODY_TYPE"PLUMBING"
BOM_COST"PROC_VRD_VCCIN_CPU0"
ROOM"PVCCIN_CPU0_PWR_VR"
CDS_LIB"mstr_symbols";
"A\NAC"4;
%"CAP"
"1","(2050,3500)","0","mstr_discrete","I134";
;
CDS_SEC"1"
$SEC"1"
CDS_LOCATION"CT61"
ROOM"VDDQ_KLM_PWR_VR"
CDS_LIB"mstr_discrete"
STATUS"NOPOP"
LOCATION"CT61"
PACK_TYPE"0402LF"
VALUE"1000PF"
PART_NUMBER"A36096-046"
MATERIAL"X7R"
TOLERANCE"10%"
VOLTAGE"50V";
"A"
$PN"1"19;
"B"
$PN"2"5;
%"GND"
"1","(2050,3300)","0","mstr_symbols","I135";
;
HDL_POWER"GND"
SIZE"1B"
BODY_TYPE"PLUMBING"
VOLTAGE"0"
ROOM"VDDQ_KLM_PWR_VR"
CDS_LIB"mstr_symbols";
"A\NAC"5;
%"GND"
"1","(50,2725)","0","mstr_symbols","I136";
;
CDS_LIB"mstr_symbols"
BODY_TYPE"PLUMBING"
ROOM"PVCCIN_CPU0_PWR_VR"
BOM_COST"PROC_VRD_VCCIN_CPU0"
SIZE"1B"
VOLTAGE"0"
HDL_POWER"GND";
"A\NAC"6;
%"CAP_A"
"1","(50,2975)","0","dev_discrete","I137";
;
CDS_SEC"1"
$SEC"1"
CDS_LOCATION"CT63"
CDS_LIB"dev_discrete"
ROOM"PVCCIN_CPU0_PWR_VR"
VOLTAGE"16V"
TOLERANCE"10%"
MATERIAL"X7R"
PART_NUMBER"A36096-030"
PACK_TYPE"0402V"
VALUE"0.1UF"
LOCATION"CT63"
STATUS"NOPOP";
"B"
$PN"2"6;
"A"
$PN"1"31;
%"RES"
"1","(-950,3250)","0","mstr_discrete","I139";
;
CDS_SEC"1"
$SEC"1"
CDS_LOCATION"RT41"
ROOM"BMC_DEBUG_HEADER"
BOM_COST"DEBUG"
CDS_LIB"mstr_discrete"
MATERIAL"CHIP"
TOLERANCE"5%"
PART_NUMBER"G21497-005"
VALUE"0.0"
PACK_TYPE"0402"
WATTAGE"1/16W"
LOCATION"RT41";
"B"
$PN"2"24;
"A"
$PN"1"26;
%"CAPP"
"1","(3375,2200)","2","mstr_discrete","I20";
;
CDS_SEC"1"
BOM_COST"PROC_VRD_PVCCIO_CPU1"
CDS_LOCATION"C4E7"
ROOM"PVCCIO_CPU1"
CDS_LIB"mstr_discrete"
SEC_TYPE"3018"
SEC"1"
PART_NUMBER"699013-049"
MATERIAL"ALUM"
VOLTAGE"2.5V"
PACK_TYPE"3018"
TOLERANCE"20%"
VALUE"470UF"
LOCATION"C4E7";
"B"
$PN"2"11;
"A"
$PN"1"8;
%"CAPP"
"1","(2900,2200)","2","mstr_discrete","I21";
;
CDS_SEC"1"
CDS_LIB"mstr_discrete"
CDS_LOCATION"C6R12"
BOM_COST"PROC_VRD_PVCCIO_CPU1"
SEC_TYPE"3018"
SEC"1"
ROOM"PVCCIO_CPU1"
VALUE"470UF"
LOCATION"C6R12"
PART_NUMBER"699013-049"
MATERIAL"ALUM"
VOLTAGE"2.5V"
PACK_TYPE"3018"
TOLERANCE"20%";
"B"
$PN"2"11;
"A"
$PN"1"8;
%"CAPP"
"1","(2425,2200)","2","mstr_discrete","I24";
;
CDS_SEC"1"
CDS_LIB"mstr_discrete"
CDS_LOCATION"C6R5"
SEC_TYPE"3018"
BOM_COST"PROC_VRD_PVCCIO_CPU1"
SEC"1"
ROOM"PVCCIO_CPU1"
PART_NUMBER"699013-049"
VALUE"470UF"
MATERIAL"ALUM"
VOLTAGE"2.5V"
PACK_TYPE"3018"
TOLERANCE"20%"
LOCATION"C6R5";
"B"
$PN"2"11;
"A"
$PN"1"8;
%"GND"
"1","(1275,1650)","0","mstr_symbols","I28";
;
HDL_POWER"GND"
ROOM"PVCCIO_CPU1"
BOM_COST"PROC_VRD_PVCCIO_CPU1"
VOLTAGE"0.0V"
BODY_TYPE"PLUMBING"
SIZE"1B"
CDS_LIB"mstr_symbols";
"A\NAC"7;
%"CAP"
"1","(1275,1900)","2","mstr_discrete","I29";
;
CDS_SEC"1"
SEC"1"
SEC_TYPE"1210"
ROOM"PVCCIO_CPU1"
BOM_COST"PROC_VRD_PVCCIO_CPU1"
CDS_LOCATION"C4E8"
CDS_LIB"mstr_discrete"
PART_NUMBER"644066-127"
LOCATION"C4E8"
VALUE"100UF"
PACK_TYPE"1210"
VOLTAGE"16V"
TOLERANCE"20%"
MATERIAL"X5R";
"A"
$PN"1"9;
"B"
$PN"2"7;
%"PVCCIO_CPU1"
"1","(3375,2550)","0","mstr_symbols","I3";
;
VOLTAGE"1.1V"
BODY_TYPE"PLUMBING"
CDS_LIB"mstr_symbols"
HDL_POWER"PVCCIO_CPU1";
"G\NAC"8;
%"UNIVERSAL_POWER"
"1","(1650,2225)","0","mstr_symbols","I30";
;
CDS_LIB"mstr_symbols"
HDL_POWER"VR_FET_SW_P12V_STBY_PVCCIN_CPU0";
"A"9;
%"CAP"
"1","(700,1875)","0","mstr_discrete","I31";
;
CDS_SEC"1"
ROOM"PVCCIO_CPU1"
BOM_COST"PROC_VRD_PVCCIO_CPU1"
SEC_TYPE"1210"
SEC"1"
CDS_LOCATION"C4E14"
CDS_LIB"mstr_discrete"
LOCATION"C4E14"
VALUE"100UF"
VOLTAGE"16V"
MATERIAL"X5R"
TOLERANCE"20%"
PACK_TYPE"1210"
PART_NUMBER"644066-127";
"A"
$PN"1"9;
"B"
$PN"2"10;
%"GND"
"1","(700,1650)","0","mstr_symbols","I32";
;
HDL_POWER"GND"
BOM_COST"PROC_VRD_PVCCIO_CPU1"
ROOM"PVCCIO_CPU1"
VOLTAGE"0.0V"
BODY_TYPE"PLUMBING"
SIZE"1B"
CDS_LIB"mstr_symbols";
"A\NAC"10;
%"GND"
"1","(3375,1900)","0","mstr_symbols","I6";
;
BOM_COST"PROC_VRD_PVCCIO_CPU1"
ROOM"PVCCIO_CPU1"
BODY_TYPE"PLUMBING"
SIZE"1B"
CDS_LIB"mstr_symbols"
VOLTAGE"0"
HDL_POWER"GND";
"A\NAC"11;
%"PVCCIO_CPU1"
"1","(3875,3275)","0","mstr_symbols","I64";
;
BODY_TYPE"PLUMBING"
VOLTAGE"1.1V"
CDS_LIB"mstr_symbols"
HDL_POWER"PVCCIO_CPU1"
ROOM"PVCCIO_CPU1"
BOM_COST"PROC_VRD_PVCCIO_CPU1";
"G\NAC"12;
%"CAP_A"
"1","(3125,3000)","0","dev_discrete","I65";
;
CDS_LIB"dev_discrete"
CDS_LOCATION"C7R1"
CDS_SEC"1"
BOM_COST"PROC_VRD_PVCCIO_CPU1"
SEC_TYPE"0603V"
SEC"1"
ROOM"PVCCIO_CPU1"
PACK_TYPE"0603V"
VOLTAGE"4V"
MATERIAL"X6S"
TOLERANCE"20%"
PART_NUMBER"E15431-004"
VALUE"22.0UF"
LOCATION"C7R1";
"B"
$PN"2"13;
"A"
$PN"1"12;
%"GND"
"1","(3875,2675)","0","mstr_symbols","I66";
;
ROOM"PVCCIO_CPU1"
BOM_COST"PROC_VRD_PVCCIO_CPU1"
BODY_TYPE"PLUMBING"
VOLTAGE"0.0V"
SIZE"1B"
CDS_LIB"mstr_symbols"
HDL_POWER"GND";
"A\NAC"13;
%"INDUCTOR"
"1","(2550,3175)","0","mstr_discrete","I67";
;
CDS_LOCATION"L4E2"
CDS_LIB"mstr_discrete"
ROOM"PVCCIO_CPU1"
CDS_SEC"1"
$SEC"1"
MATERIAL"IND"
LOCATION"L4E2"
VALUE"150NH"
PACK_TYPE"SM"
PART_NUMBER"D92183-021";
"INA\NAC"
$PN"1"20;
"INB\NAC"
$PN"2"12;
%"GND"
"1","(1500,2800)","0","mstr_symbols","I68";
;
ROOM"PVCCIO_CPU1"
BOM_COST"PROC_VRD_PVCCIO_CPU1"
BODY_TYPE"PLUMBING"
VOLTAGE"0.0V"
CDS_LIB"mstr_symbols"
HDL_POWER"GND"
SIZE"1B";
"A\NAC"14;
%"RES"
"1","(-1875,4300)","0","mstr_discrete","I71";
;
CDS_SEC"1"
CDS_LIB"mstr_discrete"
CDS_LOCATION"R6R5"
SEC"1"
SEC_TYPE"0402"
ROOM"PVCCIO_CPU1"
VALUE"1.0"
TOLERANCE"1%"
LOCATION"R6R5"
MATERIAL"CHIP"
PACK_TYPE"0402"
PART_NUMBER"G21796-090"
WATTAGE"1/16W";
"B"
$PN"2"16;
"A"
$PN"1"30;
%"CAP"
"1","(-1425,3750)","0","mstr_discrete","I73";
;
CDS_SEC"1"
CDS_LIB"mstr_discrete"
CDS_LOCATION"C4E23"
SEC"1"
SEC_TYPE"0402"
ROOM"PVCCIO_CPU1"
PACK_TYPE"0402"
TOLERANCE"10%"
LOCATION"C4E23"
VALUE"0.22UF"
PART_NUMBER"A36096-155"
MATERIAL"X7R"
VOLTAGE"16V";
"A"
$PN"1"16;
"B"
$PN"2"15;
%"CAP_A"
"1","(-1575,3775)","2","dev_discrete","I74";
;
CDS_LOCATION"C4E28"
CDS_LIB"dev_discrete"
SEC_TYPE"0402V"
CDS_SEC"1"
SEC"1"
ROOM"PVCCIO_CPU1"
TOLERANCE"10%"
MATERIAL"X6S"
VALUE"1.0UF"
LOCATION"C4E28"
VOLTAGE"6.3V"
PART_NUMBER"D97712-004"
PACK_TYPE"0402V";
"B"
$PN"2"15;
"A"
$PN"1"16;
%"CAP"
"1","(-2125,3700)","0","mstr_discrete","I76";
;
CDS_SEC"1"
CDS_LOCATION"C4E22"
CDS_LIB"mstr_discrete"
ROOM"PVCCIO_CPU1"
SEC"1"
SEC_TYPE"0402"
MATERIAL"X6S"
VOLTAGE"16V"
PACK_TYPE"0402"
VALUE"1.0UF"
PART_NUMBER"D97712-011"
LOCATION"C4E22"
TOLERANCE"10%";
"A"
$PN"1"30;
"B"
$PN"2"15;
%"CAP_A"
"1","(-2375,3725)","0","dev_discrete","I77";
;
CDS_LIB"dev_discrete"
CDS_LOCATION"C4E13"
CDS_SEC"1"
SEC_TYPE"0402V"
SEC"1"
ROOM"PVCCIO_CPU1"
PACK_TYPE"0402V"
MATERIAL"X7R"
VOLTAGE"16V"
TOLERANCE"10%"
VALUE"0.1UF"
LOCATION"C4E13"
PART_NUMBER"A36096-030";
"B"
$PN"2"15;
"A"
$PN"1"17;
%"CAP"
"1","(-1675,3125)","2","mstr_discrete","I78";
;
CDS_SEC"1"
ROOM"PVCCIO_CPU1"
SPOF"TRUE"
SEC"1"
SEC_TYPE"0402"
CDS_LIB"mstr_discrete"
CDS_LOCATION"C4E18"
TOLERANCE"10%"
PACK_TYPE"0402"
MATERIAL"X7R"
LOCATION"C4E18"
VALUE"0.220UF"
VOLTAGE"16V"
PART_NUMBER"A36096-104";
"A"
$PN"1"26;
"B"
$PN"2"23;
%"CAP"
"1","(-2600,3700)","0","mstr_discrete","I79";
;
CDS_SEC"1"
CDS_LIB"mstr_discrete"
CDS_LOCATION"C4E15"
SEC"1"
SEC_TYPE"0402"
ROOM"PVCCIO_CPU1"
PACK_TYPE"0402"
PART_NUMBER"D97712-011"
MATERIAL"X6S"
VOLTAGE"16V"
TOLERANCE"10%"
VALUE"1.0UF"
LOCATION"C4E15";
"A"
$PN"1"17;
"B"
$PN"2"15;
%"CAP"
"1","(1650,1900)","2","mstr_discrete","I8";
;
CDS_SEC"1"
$SEC"1"
ROOM"PVCCIO_CPU1"
CDS_LOCATION"C4E9"
BOM_COST"PROC_VRD_PVCCIO_CPU1"
CDS_LIB"mstr_discrete"
PART_NUMBER"644066-127"
LOCATION"C4E9"
VALUE"100UF"
TOLERANCE"20%"
PACK_TYPE"1210"
VOLTAGE"16V"
MATERIAL"X5R";
"A"
$PN"1"9;
"B"
$PN"2"18;
%"CAP"
"1","(-2825,3725)","0","mstr_discrete","I80";
;
CDS_SEC"1"
CDS_LIB"mstr_discrete"
CDS_LOCATION"C6R14"
SEC"1"
SEC_TYPE"0805"
ROOM"PVCCIO_CPU1"
PACK_TYPE"0805"
MATERIAL"X6S"
VOLTAGE"16V"
TOLERANCE"10%"
VALUE"10UF"
LOCATION"C6R14"
PART_NUMBER"C95333-007";
"A"
$PN"1"17;
"B"
$PN"2"15;
%"CAP"
"1","(-3050,3700)","0","mstr_discrete","I81";
;
CDS_SEC"1"
CDS_LIB"mstr_discrete"
CDS_LOCATION"C6R10"
ROOM"PVCCIO_CPU1"
SEC"1"
SEC_TYPE"0805"
PACK_TYPE"0805"
PART_NUMBER"C95333-007"
LOCATION"C6R10"
VALUE"10UF"
MATERIAL"X6S"
VOLTAGE"16V"
TOLERANCE"10%";
"A"
$PN"1"17;
"B"
$PN"2"15;
%"CAP"
"1","(-3275,3725)","0","mstr_discrete","I83";
;
CDS_SEC"1"
CDS_LIB"mstr_discrete"
CDS_LOCATION"C6R8"
SEC_TYPE"0805"
SEC"1"
ROOM"PVCCIO_CPU1"
PACK_TYPE"0805"
MATERIAL"X6S"
VOLTAGE"16V"
TOLERANCE"10%"
VALUE"10UF"
LOCATION"C6R8"
PART_NUMBER"C95333-007";
"A"
$PN"1"17;
"B"
$PN"2"15;
%"GND"
"1","(-3275,3375)","0","mstr_symbols","I84";
;
BOM_COST"PROC_VRD_PVCCIO_CPU1"
ROOM"PVCCIO_CPU1"
SIZE"1B"
CDS_LIB"mstr_symbols"
BODY_TYPE"PLUMBING"
VOLTAGE"0.0V"
HDL_POWER"GND";
"A\NAC"15;
%"P5V_STBY"
"1","(-900,4400)","0","mstr_symbols","I88";
;
HDL_POWER"P5V_STBY"
VOLTAGE"5.0V"
BODY_TYPE"PLUMBING"
SIZE"1B"
CDS_LIB"mstr_symbols";
"G\NAC"16;
%"UNIVERSAL_POWER"
"1","(-3275,4250)","0","mstr_symbols","I89";
;
CDS_LIB"mstr_symbols"
HDL_POWER"VR_FET_SW_P12V_STBY_PVCCIN_CPU0";
"A"17;
%"GND"
"1","(1650,1625)","0","mstr_symbols","I9";
;
HDL_POWER"GND"
ROOM"PVCCIO_CPU1"
BOM_COST"PROC_VRD_PVCCIO_CPU1"
VOLTAGE"0.0V"
CDS_LIB"mstr_symbols"
BODY_TYPE"PLUMBING"
SIZE"1B";
"A\NAC"18;
%"CAP_A"
"1","(-1725,1575)","0","dev_discrete","I96";
;
CDS_SEC"1"
CDS_LIB"dev_discrete"
BOM_COST"PROC_VRD_VCCIO_CPU1"
CDS_LOCATION"C3D27"
ROOM"PVCCIO_CPU1"
SEC"1"
SEC_TYPE"0402V"
TOLERANCE"10%"
VOLTAGE"16V"
PACK_TYPE"0402V"
VALUE"0.1UF"
PART_NUMBER"A36096-030"
LOCATION"C3D27"
MATERIAL"EMPTY";
"B"
$PN"2"36;
"A"
$PN"1"35;
END.
